(kicad_pcb
	(version 20241229)
	(generator "pcbnew")
	(generator_version "9.0")
	(general
		(thickness 1.294)
		(legacy_teardrops no)
	)
	(paper "A3")
	(title_block
		(title "Kintex 410T devboard")
		(date "2024-04-03")
		(rev "1.1.2")
		(comment 9 "footprints 387-390 of 975")
	)
	(layers
		(0 "F.Cu" mixed)
		(4 "In1.Cu" power)
		(6 "In2.Cu" power)
		(8 "In3.Cu" mixed)
		(10 "In4.Cu" power)
		(12 "In5.Cu" mixed)
		(14 "In6.Cu" power)
		(16 "In7.Cu" mixed)
		(18 "In8.Cu" power)
		(2 "B.Cu" mixed)
		(9 "F.Adhes" user "F.Adhesive")
		(11 "B.Adhes" user "B.Adhesive")
		(13 "F.Paste" user)
		(15 "B.Paste" user)
		(5 "F.SilkS" user "F.Silkscreen")
		(7 "B.SilkS" user "B.Silkscreen")
		(1 "F.Mask" user)
		(3 "B.Mask" user)
		(17 "Dwgs.User" user "User.Drawings")
		(19 "Cmts.User" user "User.Comments")
		(21 "Eco1.User" user "User.Eco1")
		(23 "Eco2.User" user "User.Eco2")
		(25 "Edge.Cuts" user)
		(27 "Margin" user)
		(31 "F.CrtYd" user "F.Courtyard")
		(29 "B.CrtYd" user "B.Courtyard")
		(35 "F.Fab" user)
		(33 "B.Fab" user)
	)
	(footprint "antmicro-footprints:VQFN-20_5x5x1mm_P0.65mm"
		(layer "F.Cu")
		(at 252.6 174.9)
		(property "Reference" "U7"
			(at -0.75 -2.9 0)
			(layer "F.SilkS")
			(effects
				(font
					(size 0.7 0.7)
					(thickness 0.15)
				)
				(justify left bottom)
			)
		)
		(property "Value" "TPS2372-3RGWR"
			(at 0 3.883 0)
			(layer "F.Fab")
			(effects
				(font
					(size 0.7 0.7)
					(thickness 0.15)
				)
				(justify left bottom)
			)
		)
		(property "Description" "PoE interface"
			(at 0 0 0)
			(layer "F.Fab")
			(hide yes)
			(effects
				(font
					(size 1.27 1.27)
					(thickness 0.15)
				)
			)
		)
		(property "Author" "Antmicro"
			(at 0 0 0)
			(layer "F.Fab")
			(hide yes)
			(effects
				(font
					(size 1 1)
					(thickness 0.15)
				)
			)
		)
		(property "License" "Apache-2.0"
			(at 0 0 0)
			(layer "F.Fab")
			(hide yes)
			(effects
				(font
					(size 1 1)
					(thickness 0.15)
				)
			)
		)
		(property "MPN" "TPS2372-3RGWR"
			(at 0 0 0)
			(layer "F.Fab")
			(hide yes)
			(effects
				(font
					(size 1 1)
					(thickness 0.15)
				)
			)
		)
		(property "Manufacturer" "Texas Instruments"
			(at 0 0 0)
			(layer "F.Fab")
			(hide yes)
			(effects
				(font
					(size 1 1)
					(thickness 0.15)
				)
			)
		)
		(sheetname "Power supply")
		(sheetfile "power-supply.kicad_sch")
		(attr smd)
		(fp_line
			(start -2.5 2.499)
			(end -2.5 1.789)
			(stroke
				(width 0.15)
				(type solid)
			)
			(layer "F.SilkS")
		)
		(fp_line
			(start -2.5 2.499)
			(end -1.79 2.499)
			(stroke
				(width 0.15)
				(type solid)
			)
			(layer "F.SilkS")
		)
		(fp_line
			(start -1.625 -2.5)
			(end -2.5 -2.5)
			(stroke
				(width 0.15)
				(type solid)
			)
			(layer "F.SilkS")
		)
		(fp_line
			(start 2.499 -2.5)
			(end 1.789 -2.5)
			(stroke
				(width 0.15)
				(type solid)
			)
			(layer "F.SilkS")
		)
		(fp_line
			(start 2.499 -2.5)
			(end 2.499 -1.79)
			(stroke
				(width 0.15)
				(type solid)
			)
			(layer "F.SilkS")
		)
		(fp_line
			(start 2.499 2.499)
			(end 1.789 2.499)
			(stroke
				(width 0.15)
				(type solid)
			)
			(layer "F.SilkS")
		)
		(fp_line
			(start 2.499 2.499)
			(end 2.499 1.789)
			(stroke
				(width 0.15)
				(type solid)
			)
			(layer "F.SilkS")
		)
		(fp_circle
			(center -2.775 -1.875)
			(end -2.725 -1.825)
			(stroke
				(width 0.15)
				(type solid)
			)
			(fill yes)
			(layer "F.SilkS")
		)
		(fp_poly
			(pts
				(xy -1.081 -1.081) (xy -0.11 -1.081) (xy -0.11 -0.09) (xy -1.081 -0.09)
			)
			(stroke
				(width 0.01)
				(type solid)
			)
			(fill yes)
			(layer "F.Paste")
		)
		(fp_poly
			(pts
				(xy -1.081 0.088) (xy -0.11 0.088) (xy -0.11 1.08) (xy -1.081 1.08)
			)
			(stroke
				(width 0.01)
				(type solid)
			)
			(fill yes)
			(layer "F.Paste")
		)
		(fp_poly
			(pts
				(xy 0.108 -1.081) (xy 1.08 -1.081) (xy 1.08 -0.09) (xy 0.108 -0.09)
			)
			(stroke
				(width 0.01)
				(type solid)
			)
			(fill yes)
			(layer "F.Paste")
		)
		(fp_poly
			(pts
				(xy 0.108 0.088) (xy 1.08 0.088) (xy 1.08 1.08) (xy 0.108 1.08)
			)
			(stroke
				(width 0.01)
				(type solid)
			)
			(fill yes)
			(layer "F.Paste")
		)
		(fp_rect
			(start -2.95 -2.95)
			(end 2.95 2.95)
			(stroke
				(width 0.05)
				(type solid)
			)
			(fill no)
			(layer "F.CrtYd")
		)
		(fp_line
			(start -2.5 -1.65)
			(end -1.65 -2.5)
			(stroke
				(width 0.15)
				(type solid)
			)
			(layer "F.Fab")
		)
		(fp_line
			(start -2.5 2.499)
			(end -2.5 -1.65)
			(stroke
				(width 0.15)
				(type solid)
			)
			(layer "F.Fab")
		)
		(fp_line
			(start 2.499 -2.5)
			(end -1.65 -2.5)
			(stroke
				(width 0.15)
				(type solid)
			)
			(layer "F.Fab")
		)
		(fp_line
			(start 2.499 2.499)
			(end -2.5 2.499)
			(stroke
				(width 0.15)
				(type solid)
			)
			(layer "F.Fab")
		)
		(fp_line
			(start 2.499 2.499)
			(end 2.499 -2.5)
			(stroke
				(width 0.15)
				(type solid)
			)
			(layer "F.Fab")
		)
		(pad "1" smd roundrect
			(at -2.327 -1.301)
			(size 0.75 0.31)
			(layers "F.Cu" "F.Mask" "F.Paste")
			(roundrect_rratio 0.25)
			(net 698 "/Power supply/VDD")
			(pinfunction "VDD")
			(pintype "power_in")
		)
		(pad "2" smd roundrect
			(at -2.327 -0.652)
			(size 0.75 0.31)
			(layers "F.Cu" "F.Mask" "F.Paste")
			(roundrect_rratio 0.25)
			(net 887 "/Power supply/DEN")
			(pinfunction "DEN")
			(pintype "input")
		)
		(pad "3" smd roundrect
			(at -2.327 0)
			(size 0.75 0.31)
			(layers "F.Cu" "F.Mask" "F.Paste")
			(roundrect_rratio 0.25)
			(net 885 "/Power supply/CLSA")
			(pinfunction "CLSA")
			(pintype "input")
		)
		(pad "4" smd roundrect
			(at -2.327 0.65)
			(size 0.75 0.31)
			(layers "F.Cu" "F.Mask" "F.Paste")
			(roundrect_rratio 0.25)
			(net 697 "/Power supply/VSS")
			(pinfunction "VSSA")
			(pintype "power_in")
		)
		(pad "5" smd roundrect
			(at -2.327 1.3)
			(size 0.75 0.31)
			(layers "F.Cu" "F.Mask" "F.Paste")
			(roundrect_rratio 0.25)
			(net 697 "/Power supply/VSS")
			(pinfunction "VSSB")
			(pintype "power_in")
		)
		(pad "6" smd roundrect
			(at -1.301 2.325)
			(size 0.31 0.75)
			(layers "F.Cu" "F.Mask" "F.Paste")
			(roundrect_rratio 0.25)
			(net 886 "/Power supply/CLSB")
			(pinfunction "CLSB")
			(pintype "input")
		)
		(pad "7" smd roundrect
			(at -0.652 2.325)
			(size 0.31 0.75)
			(layers "F.Cu" "F.Mask" "F.Paste")
			(roundrect_rratio 0.25)
			(net 882 "/Power supply/REF")
			(pinfunction "REF")
			(pintype "input")
		)
		(pad "8" smd roundrect
			(at 0 2.325)
			(size 0.31 0.75)
			(layers "F.Cu" "F.Mask" "F.Paste")
			(roundrect_rratio 0.25)
			(net 881 "/Power supply/AMPS_CTL")
			(pinfunction "AMPS_CTL")
			(pintype "input")
		)
		(pad "9" smd roundrect
			(at 0.65 2.325)
			(size 0.31 0.75)
			(layers "F.Cu" "F.Mask" "F.Paste")
			(roundrect_rratio 0.25)
			(net 883 "/Power supply/MPS_DUTY")
			(pinfunction "MPS_DUTY")
			(pintype "input")
		)
		(pad "10" smd roundrect
			(at 1.3 2.325)
			(size 0.31 0.75)
			(layers "F.Cu" "F.Mask" "F.Paste")
			(roundrect_rratio 0.25)
			(net 1148 "unconnected-(U7-~{AUTCLS}-Pad10)")
			(pinfunction "~{AUTCLS}")
			(pintype "input+no_connect")
		)
		(pad "11" smd roundrect
			(at 2.325 1.3)
			(size 0.75 0.31)
			(layers "F.Cu" "F.Mask" "F.Paste")
			(roundrect_rratio 0.25)
			(net 699 "GNDD")
			(pinfunction "RTNA")
			(pintype "output")
		)
		(pad "12" smd roundrect
			(at 2.325 0.65)
			(size 0.75 0.31)
			(layers "F.Cu" "F.Mask" "F.Paste")
			(roundrect_rratio 0.25)
			(net 699 "GNDD")
			(pinfunction "RTNB")
			(pintype "output")
		)
		(pad "13" smd roundrect
			(at 2.325 0)
			(size 0.75 0.31)
			(layers "F.Cu" "F.Mask" "F.Paste")
			(roundrect_rratio 0.25)
			(net 889 "/Power supply/PG")
			(pinfunction "PG")
			(pintype "output")
		)
		(pad "14" smd roundrect
			(at 2.325 -0.652)
			(size 0.75 0.31)
			(layers "F.Cu" "F.Mask" "F.Paste")
			(roundrect_rratio 0.25)
			(net 1149 "unconnected-(U7-NC-Pad14)")
			(pinfunction "NC")
			(pintype "no_connect")
		)
		(pad "15" smd roundrect
			(at 2.325 -1.301)
			(size 0.75 0.31)
			(layers "F.Cu" "F.Mask" "F.Paste")
			(roundrect_rratio 0.25)
			(net 1150 "unconnected-(U7-NC-Pad15)")
			(pinfunction "NC")
			(pintype "no_connect")
		)
		(pad "16" smd roundrect
			(at 1.3 -2.327)
			(size 0.31 0.75)
			(layers "F.Cu" "F.Mask" "F.Paste")
			(roundrect_rratio 0.25)
			(net 1151 "unconnected-(U7-IRSHDL_EN-Pad16)")
			(pinfunction "IRSHDL_EN")
			(pintype "output+no_connect")
		)
		(pad "17" smd roundrect
			(at 0.65 -2.327)
			(size 0.31 0.75)
			(layers "F.Cu" "F.Mask" "F.Paste")
			(roundrect_rratio 0.25)
			(net 1152 "unconnected-(U7-TPL-Pad17)")
			(pinfunction "TPL")
			(pintype "output+no_connect")
		)
		(pad "18" smd roundrect
			(at 0 -2.327)
			(size 0.31 0.75)
			(layers "F.Cu" "F.Mask" "F.Paste")
			(roundrect_rratio 0.25)
			(net 1153 "unconnected-(U7-TPH-Pad18)")
			(pinfunction "TPH")
			(pintype "output+no_connect")
		)
		(pad "19" smd roundrect
			(at -0.652 -2.327)
			(size 0.31 0.75)
			(layers "F.Cu" "F.Mask" "F.Paste")
			(roundrect_rratio 0.25)
			(net 1154 "unconnected-(U7-~{BT}-Pad19)")
			(pinfunction "~{BT}")
			(pintype "output+no_connect")
		)
		(pad "20" smd roundrect
			(at -1.301 -2.327)
			(size 0.31 0.75)
			(layers "F.Cu" "F.Mask" "F.Paste")
			(roundrect_rratio 0.25)
			(net 1155 "unconnected-(U7-NC-Pad20)")
			(pinfunction "NC")
			(pintype "no_connect")
		)
		(pad "21" smd rect
			(at 0 0)
			(size 2.2 2.2)
			(layers "F.Cu" "F.Mask")
			(net 697 "/Power supply/VSS")
			(pinfunction "PAD_VSSC")
			(pintype "power_in")
		)
	)
	(footprint "antmicro-footprints:Oscillator_SMD_Abracon_AX3_3.2x2.5x1mm"
		(layer "F.Cu")
		(at 189.915001 150.886 90)
		(property "Reference" "Y6"
			(at 0.686 -2.05 90)
			(layer "F.SilkS")
			(effects
				(font
					(size 0.7 0.7)
					(thickness 0.15)
				)
				(justify right bottom)
			)
		)
		(property "Value" "Oscillator_200MHz_AX3DC"
			(at 0 2.8 90)
			(layer "F.Fab")
			(effects
				(font
					(size 0.7 0.7)
					(thickness 0.15)
				)
				(justify left bottom)
			)
		)
		(property "Description" "150 MHz XO (Standard) LVDS Oscillator 1.8V Enable/Disable 6-SMD, No Lead"
			(at 0 0 90)
			(layer "F.Fab")
			(hide yes)
			(effects
				(font
					(size 1.27 1.27)
					(thickness 0.15)
				)
			)
		)
		(property "Author" "Antmicro"
			(at 340.801001 -39.029001 0)
			(layer "F.Fab")
			(hide yes)
			(effects
				(font
					(size 1 1)
					(thickness 0.15)
				)
			)
		)
		(property "License" "Apache-2.0"
			(at 340.801001 -39.029001 0)
			(layer "F.Fab")
			(hide yes)
			(effects
				(font
					(size 1 1)
					(thickness 0.15)
				)
			)
		)
		(property "MPN" "AX3DCF1-200.0000"
			(at 340.801001 -39.029001 0)
			(layer "F.Fab")
			(hide yes)
			(effects
				(font
					(size 1 1)
					(thickness 0.15)
				)
			)
		)
		(property "Manufacturer" "Abracon"
			(at 340.801001 -39.029001 0)
			(layer "F.Fab")
			(hide yes)
			(effects
				(font
					(size 1 1)
					(thickness 0.15)
				)
			)
		)
		(property "Val" "200 MHz"
			(at 340.801001 -39.029001 0)
			(layer "F.Fab")
			(hide yes)
			(effects
				(font
					(size 1 1)
					(thickness 0.15)
				)
			)
		)
		(sheetname "Clocks")
		(sheetfile "clocks.kicad_sch")
		(attr smd)
		(fp_line
			(start 1.5 -1.8)
			(end -1.5 -1.8)
			(stroke
				(width 0.12)
				(type solid)
			)
			(layer "F.SilkS")
		)
		(fp_line
			(start -1.5 -1.8)
			(end -1.5 -1.5)
			(stroke
				(width 0.12)
				(type solid)
			)
			(layer "F.SilkS")
		)
		(fp_line
			(start 1.5 -1.5)
			(end 1.5 -1.8)
			(stroke
				(width 0.12)
				(type solid)
			)
			(layer "F.SilkS")
		)
		(fp_line
			(start -1.5 1.5)
			(end -1.5 1.8)
			(stroke
				(width 0.12)
				(type solid)
			)
			(layer "F.SilkS")
		)
		(fp_line
			(start 1.5 1.8)
			(end 1.5 1.5)
			(stroke
				(width 0.12)
				(type solid)
			)
			(layer "F.SilkS")
		)
		(fp_line
			(start -1.5 1.8)
			(end 1.5 1.8)
			(stroke
				(width 0.12)
				(type solid)
			)
			(layer "F.SilkS")
		)
		(fp_circle
			(center -1.7 -1.9)
			(end -1.7 -1.85)
			(stroke
				(width 0.15)
				(type solid)
			)
			(fill yes)
			(layer "F.SilkS")
		)
		(fp_rect
			(start 1.6 -1.9)
			(end -1.6 1.9)
			(stroke
				(width 0.05)
				(type solid)
			)
			(fill no)
			(layer "F.CrtYd")
		)
		(fp_line
			(start -0.6 -1.6)
			(end -1.3 -0.9)
			(stroke
				(width 0.15)
				(type solid)
			)
			(layer "F.Fab")
		)
		(fp_rect
			(start 1.3 -1.601)
			(end -1.3 1.599)
			(stroke
				(width 0.15)
				(type solid)
			)
			(fill no)
			(layer "F.Fab")
		)
		(pad "1" smd rect
			(at -0.8 -1.199)
			(size 0.9 1.1)
			(layers "F.Cu" "F.Mask" "F.Paste")
			(net 640 "/Clocks/LVDS_XO_200M_ENA")
			(pinfunction "EN")
			(pintype "input")
		)
		(pad "2" smd rect
			(at -0.8 0)
			(size 0.9 1.1)
			(layers "F.Cu" "F.Mask" "F.Paste")
			(net 1412 "unconnected-(Y6-NC-Pad2)")
			(pinfunction "NC")
			(pintype "no_connect")
		)
		(pad "3" smd rect
			(at -0.8 1.199)
			(size 0.9 1.1)
			(layers "F.Cu" "F.Mask" "F.Paste")
			(net 1 "GND")
			(pinfunction "GND")
			(pintype "power_in")
		)
		(pad "4" smd rect
			(at 0.801 1.199)
			(size 0.9 1.1)
			(layers "F.Cu" "F.Mask" "F.Paste")
			(net 624 "/Clocks/SYS.CLK_P")
			(pinfunction "OUT+")
			(pintype "output")
		)
		(pad "5" smd rect
			(at 0.801 0)
			(size 0.9 1.1)
			(layers "F.Cu" "F.Mask" "F.Paste")
			(net 623 "/Clocks/SYS.CLK_N")
			(pinfunction "OUT-")
			(pintype "output")
		)
		(pad "6" smd rect
			(at 0.801 -1.199)
			(size 0.9 1.1)
			(layers "F.Cu" "F.Mask" "F.Paste")
			(net 26 "+1V8")
			(pinfunction "VCC")
			(pintype "power_in")
		)
	)
	(footprint "antmicro-footprints:C_0402_1005Metric"
		(layer "F.Cu")
		(at 231.8 124.5 180)
		(descr "Capacitor SMD 0402")
		(tags "capacitor SMD 0402")
		(property "Reference" "C217"
			(at 0.9 -0.35 0)
			(layer "F.SilkS")
			(effects
				(font
					(size 0.7 0.7)
					(thickness 0.15)
				)
				(justify right bottom)
			)
		)
		(property "Value" "C_1u_0402"
			(at 0 1.4 0)
			(layer "F.Fab")
			(effects
				(font
					(size 0.7 0.7)
					(thickness 0.15)
				)
				(justify right bottom)
			)
		)
		(property "Description" "SMD Multilayer Ceramic Capacitor, 1 µF, 10 V, 0402 [1005 Metric], ± 10%, X6S, C"
			(at 0 0 180)
			(layer "F.Fab")
			(hide yes)
			(effects
				(font
					(size 1.27 1.27)
					(thickness 0.15)
				)
			)
		)
		(property "Author" "Antmicro"
			(at 463.6 249 0)
			(layer "F.Fab")
			(hide yes)
			(effects
				(font
					(size 1 1)
					(thickness 0.15)
				)
			)
		)
		(property "Dielectric" ""
			(at 463.6 249 0)
			(layer "F.Fab")
			(hide yes)
			(effects
				(font
					(size 1 1)
					(thickness 0.15)
				)
			)
		)
		(property "License" "Apache-2.0"
			(at 463.6 249 0)
			(layer "F.Fab")
			(hide yes)
			(effects
				(font
					(size 1 1)
					(thickness 0.15)
				)
			)
		)
		(property "MPN" "C1005X6S1A105K050BC"
			(at 463.6 249 0)
			(layer "F.Fab")
			(hide yes)
			(effects
				(font
					(size 1 1)
					(thickness 0.15)
				)
			)
		)
		(property "Manufacturer" "TDK"
			(at 463.6 249 0)
			(layer "F.Fab")
			(hide yes)
			(effects
				(font
					(size 1 1)
					(thickness 0.15)
				)
			)
		)
		(property "Val" "1u"
			(at 463.6 249 0)
			(layer "F.Fab")
			(hide yes)
			(effects
				(font
					(size 1 1)
					(thickness 0.15)
				)
			)
		)
		(property "Voltage" ""
			(at 463.6 249 0)
			(layer "F.Fab")
			(hide yes)
			(effects
				(font
					(size 1 1)
					(thickness 0.15)
				)
			)
		)
		(sheetname "User GPIO + LED + button + DIP switch")
		(sheetfile "user-gpio.kicad_sch")
		(attr smd)
		(fp_rect
			(start -0.925 -0.47)
			(end 0.925 0.47)
			(stroke
				(width 0.05)
				(type default)
			)
			(fill no)
			(layer "F.CrtYd")
		)
		(fp_line
			(start 0.504 0.248)
			(end -0.494 0.248)
			(stroke
				(width 0.15)
				(type solid)
			)
			(layer "F.Fab")
		)
		(fp_line
			(start 0.504 -0.25)
			(end 0.504 0.248)
			(stroke
				(width 0.15)
				(type solid)
			)
			(layer "F.Fab")
		)
		(fp_line
			(start -0.494 0.248)
			(end -0.494 -0.25)
			(stroke
				(width 0.15)
				(type solid)
			)
			(layer "F.Fab")
		)
		(fp_line
			(start -0.494 -0.25)
			(end 0.504 -0.25)
			(stroke
				(width 0.15)
				(type solid)
			)
			(layer "F.Fab")
		)
		(pad "1" smd roundrect
			(at -0.48 0 180)
			(size 0.59 0.64)
			(layers "F.Cu" "F.Mask" "F.Paste")
			(roundrect_rratio 0.25)
			(net 1 "GND")
			(pintype "passive")
		)
		(pad "2" smd roundrect
			(at 0.48 0 180)
			(size 0.59 0.64)
			(layers "F.Cu" "F.Mask" "F.Paste")
			(roundrect_rratio 0.25)
			(net 703 "+5V")
			(pintype "passive")
		)
	)
	(footprint "antmicro-footprints:R_0402_1005Metric"
		(layer "F.Cu")
		(at 237.65 141.7 -90)
		(descr "Resistor SMD 0402")
		(tags "resistor SMD 0402")
		(property "Reference" "R181"
			(at 3.85 -6.85 270)
			(layer "F.SilkS")
			(effects
				(font
					(size 0.7 0.7)
					(thickness 0.15)
				)
				(justify left bottom)
			)
		)
		(property "Value" "R_0R_0402"
			(at 0 1.4 270)
			(layer "F.Fab")
			(effects
				(font
					(size 0.7 0.7)
					(thickness 0.15)
				)
				(justify left bottom)
			)
		)
		(property "Description" "SMD Chip Resistor, Jumper, 0 ohm, 100 mW, 0402 [1005 Metric], Thick Film, General Purpose"
			(at 0 0 270)
			(layer "F.Fab")
			(hide yes)
			(effects
				(font
					(size 1.27 1.27)
					(thickness 0.15)
				)
			)
		)
		(property "Author" "Antmicro"
			(at 95.95 379.35 0)
			(layer "F.Fab")
			(hide yes)
			(effects
				(font
					(size 1 1)
					(thickness 0.15)
				)
			)
		)
		(property "Current" "1A"
			(at 95.95 379.35 0)
			(layer "F.Fab")
			(hide yes)
			(effects
				(font
					(size 1 1)
					(thickness 0.15)
				)
			)
		)
		(property "DNP" "DNP"
			(at 95.95 379.35 0)
			(layer "F.Fab")
			(hide yes)
			(effects
				(font
					(size 1 1)
					(thickness 0.15)
				)
			)
		)
		(property "License" "Apache-2.0"
			(at 95.95 379.35 0)
			(layer "F.Fab")
			(hide yes)
			(effects
				(font
					(size 1 1)
					(thickness 0.15)
				)
			)
		)
		(property "MPN" "ERJ2GE0R00X"
			(at 95.95 379.35 0)
			(layer "F.Fab")
			(hide yes)
			(effects
				(font
					(size 1 1)
					(thickness 0.15)
				)
			)
		)
		(property "Manufacturer" "Panasonic"
			(at 95.95 379.35 0)
			(layer "F.Fab")
			(hide yes)
			(effects
				(font
					(size 1 1)
					(thickness 0.15)
				)
			)
		)
		(property "Tolerance" ""
			(at 95.95 379.35 0)
			(layer "F.Fab")
			(hide yes)
			(effects
				(font
					(size 1 1)
					(thickness 0.15)
				)
			)
		)
		(property "Val" "0R"
			(at 95.95 379.35 0)
			(layer "F.Fab")
			(hide yes)
			(effects
				(font
					(size 1 1)
					(thickness 0.15)
				)
			)
		)
		(property "dnp" ""
			(at 95.95 379.35 0)
			(layer "F.Fab")
			(hide yes)
			(effects
				(font
					(size 1 1)
					(thickness 0.15)
				)
			)
		)
		(property "exclude_from_bom" ""
			(at 95.95 379.35 0)
			(layer "F.Fab")
			(hide yes)
			(effects
				(font
					(size 1 1)
					(thickness 0.15)
				)
			)
		)
		(sheetname "USB PHY")
		(sheetfile "usb-phy.kicad_sch")
		(attr smd exclude_from_bom)
		(fp_rect
			(start -0.925 -0.47)
			(end 0.925 0.47)
			(stroke
				(width 0.05)
				(type default)
			)
			(fill no)
			(layer "F.CrtYd")
		)
		(fp_rect
			(start -0.5 -0.25)
			(end 0.5 0.25)
			(stroke
				(width 0.15)
				(type solid)
			)
			(fill no)
			(layer "F.Fab")
		)
		(pad "1" smd roundrect
			(at -0.48 0 270)
			(size 0.59 0.64)
			(layers "F.Cu" "F.Mask" "F.Paste")
			(roundrect_rratio 0.25)
			(net 934 "/USB PHY/SPI_EN")
			(pintype "passive")
		)
		(pad "2" smd roundrect
			(at 0.48 0 270)
			(size 0.59 0.64)
			(layers "F.Cu" "F.Mask" "F.Paste")
			(roundrect_rratio 0.25)
			(net 372 "Net-(U23-OE)")
			(pintype "passive")
		)
	)
)
